(kicad_pcb
	(version 20241229)
	(generator "pcbnew")
	(generator_version "9.0")
	(general
		(thickness 1.63)
		(legacy_teardrops no)
	)
	(paper "A4")
	(title_block
		(title "CM4 Baseboard")
		(date "2026-01-05")
		(rev "1.1.1")
		(company "Antmicro Ltd")
		(comment 1 "www.antmicro.com")
		(comment 9 "footprints 454-457 of 506")
	)
	(layers
		(0 "F.Cu" signal)
		(4 "In1.Cu" power)
		(6 "In2.Cu" power)
		(8 "In3.Cu" signal)
		(10 "In4.Cu" signal)
		(2 "B.Cu" signal)
		(9 "F.Adhes" user "F.Adhesive")
		(11 "B.Adhes" user "B.Adhesive")
		(13 "F.Paste" user)
		(15 "B.Paste" user)
		(5 "F.SilkS" user "F.Silkscreen")
		(7 "B.SilkS" user "B.Silkscreen")
		(1 "F.Mask" user)
		(3 "B.Mask" user)
		(17 "Dwgs.User" user "User.Drawings")
		(19 "Cmts.User" user "User.Comments")
		(21 "Eco1.User" user "User.Eco1")
		(23 "Eco2.User" user "User.Eco2")
		(25 "Edge.Cuts" user)
		(27 "Margin" user)
		(31 "F.CrtYd" user "F.Courtyard")
		(29 "B.CrtYd" user "B.Courtyard")
		(35 "F.Fab" user)
		(33 "B.Fab" user)
	)
	(footprint "antmicro-footprints:Vishay_PowerPAK_1212-8_Single"
		(layer "B.Cu")
		(at 44.617962 156.1665 90)
		(descr "PowerPAK 1212-8 Single")
		(tags "Vishay PowerPAK 1212-8 Single")
		(property "Reference" "Q307"
			(at -2.91 0.02 180)
			(layer "B.SilkS")
			(effects
				(font
					(size 0.7 0.7)
					(thickness 0.15)
				)
				(justify right bottom mirror)
			)
		)
		(property "Value" "SQS401EN-T1_BE3"
			(at 0 -2.7 90)
			(layer "B.Fab")
			(effects
				(font
					(size 0.7 0.7)
					(thickness 0.15)
				)
				(justify right bottom mirror)
			)
		)
		(property "Datasheet" "https://www.vishay.com/docs/65529/sqs401en.pdf"
			(at 0 0 90)
			(layer "B.Fab")
			(hide yes)
			(effects
				(font
					(size 1.27 1.27)
					(thickness 0.15)
				)
			)
		)
		(property "MPN" "SQS401EN-T1_BE3"
			(at 0 0 90)
			(unlocked yes)
			(layer "B.Fab")
			(hide yes)
			(effects
				(font
					(size 1 1)
					(thickness 0.15)
				)
				(justify mirror)
			)
		)
		(property "Manufacturer" "Vishay"
			(at 0 0 90)
			(unlocked yes)
			(layer "B.Fab")
			(hide yes)
			(effects
				(font
					(size 1 1)
					(thickness 0.15)
				)
				(justify mirror)
			)
		)
		(property "Author" "Antmicro"
			(at 0 0 90)
			(unlocked yes)
			(layer "B.Fab")
			(hide yes)
			(effects
				(font
					(size 1 1)
					(thickness 0.15)
				)
				(justify mirror)
			)
		)
		(property "License" "Apache-2.0"
			(at 0 0 90)
			(unlocked yes)
			(layer "B.Fab")
			(hide yes)
			(effects
				(font
					(size 1 1)
					(thickness 0.15)
				)
				(justify mirror)
			)
		)
		(sheetname "/Supply/")
		(sheetfile "supply.kicad_sch")
		(attr smd)
		(fp_line
			(start -1.635 -1.634)
			(end 1.634 -1.634)
			(stroke
				(width 0.15)
				(type solid)
			)
			(layer "B.SilkS")
		)
		(fp_line
			(start 1.634 -1.3)
			(end 1.634 -1.634)
			(stroke
				(width 0.15)
				(type solid)
			)
			(layer "B.SilkS")
		)
		(fp_line
			(start -1.635 -1.3)
			(end -1.635 -1.634)
			(stroke
				(width 0.15)
				(type solid)
			)
			(layer "B.SilkS")
		)
		(fp_line
			(start 1.648 1.651)
			(end 1.648 1.317)
			(stroke
				(width 0.15)
				(type solid)
			)
			(layer "B.SilkS")
		)
		(fp_line
			(start -1.651 1.651)
			(end -1.651 1.317)
			(stroke
				(width 0.15)
				(type solid)
			)
			(layer "B.SilkS")
		)
		(fp_line
			(start -1.651 1.651)
			(end 1.648 1.651)
			(stroke
				(width 0.15)
				(type solid)
			)
			(layer "B.SilkS")
		)
		(fp_circle
			(center -1.9 1.4)
			(end -1.85 1.4)
			(stroke
				(width 0.15)
				(type solid)
			)
			(fill yes)
			(layer "B.SilkS")
		)
		(fp_rect
			(start -2 1.8)
			(end 2 -1.798)
			(stroke
				(width 0.05)
				(type solid)
			)
			(fill no)
			(layer "B.CrtYd")
		)
		(fp_line
			(start -1.6425 1.4175)
			(end -1.4175 1.6425)
			(stroke
				(width 0.15)
				(type solid)
			)
			(layer "B.Fab")
		)
		(fp_rect
			(start -1.651 1.651)
			(end 1.648 -1.648)
			(stroke
				(width 0.15)
				(type solid)
			)
			(fill no)
			(layer "B.Fab")
		)
		(fp_text user "${REFERENCE}"
			(at -8 -4.7 270)
			(layer "B.Fab")
			(effects
				(font
					(size 0.7 0.7)
					(thickness 0.15)
				)
				(justify left bottom mirror)
			)
		)
		(fp_text user "License: Apache-2.0"
			(at -8 -7.1 270)
			(layer "B.Fab")
			(effects
				(font
					(size 0.7 0.7)
					(thickness 0.15)
				)
				(justify left bottom mirror)
			)
		)
		(fp_text user "Author: Antmicro"
			(at -8 -5.9 270)
			(layer "B.Fab")
			(effects
				(font
					(size 0.7 0.7)
					(thickness 0.15)
				)
				(justify left bottom mirror)
			)
		)
		(pad "1" smd rect
			(at -1.436 0.99 90)
			(size 0.99 0.405)
			(layers "B.Cu" "B.Mask" "B.Paste")
			(net 21 "/Supply/VCC_IN")
			(pinfunction "S")
			(pintype "passive")
		)
		(pad "2" smd rect
			(at -1.436 0.332 90)
			(size 0.99 0.405)
			(layers "B.Cu" "B.Mask" "B.Paste")
			(net 21 "/Supply/VCC_IN")
			(pinfunction "S")
			(pintype "passive")
		)
		(pad "3" smd rect
			(at -1.436 -0.33 90)
			(size 0.99 0.405)
			(layers "B.Cu" "B.Mask" "B.Paste")
			(net 21 "/Supply/VCC_IN")
			(pinfunction "S")
			(pintype "passive")
		)
		(pad "4" smd rect
			(at -1.436 -0.988 90)
			(size 0.99 0.405)
			(layers "B.Cu" "B.Mask" "B.Paste")
			(net 17 "Net-(Q307-G)")
			(pinfunction "G")
			(pintype "input")
		)
		(pad "5" smd custom
			(at 0.557 0 90)
			(size 1.725 2.235)
			(layers "B.Cu" "B.Mask" "B.Paste")
			(net 43 "VCC")
			(pinfunction "D")
			(pintype "passive")
			(zone_connect 2)
			(options
				(clearance outline)
				(anchor rect)
			)
			(primitives
				(gr_poly
					(pts
						(xy 0.8625 -0.1275) (xy 0.8625 0.1275) (xy 1.3725 0.1275) (xy 1.3725 0.5325) (xy 0.8625 0.5325)
						(xy 0.8625 0.7875) (xy 1.3725 0.7875) (xy 1.3725 1.195) (xy 0.6125 1.195) (xy 0.6125 -1.195) (xy 1.3725 -1.195)
						(xy 1.3725 -0.7875) (xy 0.8625 -0.7875) (xy 0.8625 -0.5325) (xy 1.3725 -0.5325) (xy 1.3725 -0.1275)
					)
					(width 0)
					(fill yes)
				)
			)
		)
	)
	(footprint "antmicro-footprints:R_0402_1005Metric"
		(layer "B.Cu")
		(at 63.492962 162.2365)
		(descr "Resistor SMD 0402")
		(tags "resistor SMD 0402")
		(property "Reference" "R312"
			(at 12.495 1.7 0)
			(layer "B.SilkS")
			(effects
				(font
					(size 0.7 0.7)
					(thickness 0.15)
				)
				(justify right bottom mirror)
			)
		)
		(property "Value" "R_10k_0402"
			(at -1.011843 -1.772047 0)
			(layer "B.Fab")
			(effects
				(font
					(size 0.7 0.7)
					(thickness 0.15)
				)
				(justify right bottom mirror)
			)
		)
		(property "Datasheet" "https://www.bourns.com/docs/product-datasheets/cr.pdf"
			(at 0 0 0)
			(layer "B.Fab")
			(hide yes)
			(effects
				(font
					(size 1.27 1.27)
					(thickness 0.15)
				)
			)
		)
		(property "Manufacturer" "Bourns"
			(at 0 0 0)
			(unlocked yes)
			(layer "B.Fab")
			(hide yes)
			(effects
				(font
					(size 1 1)
					(thickness 0.15)
				)
				(justify mirror)
			)
		)
		(property "MPN" "CR0402-FX-1002GLF"
			(at 0 0 0)
			(unlocked yes)
			(layer "B.Fab")
			(hide yes)
			(effects
				(font
					(size 1 1)
					(thickness 0.15)
				)
				(justify mirror)
			)
		)
		(property "Val" "10k"
			(at 0 0 0)
			(unlocked yes)
			(layer "B.Fab")
			(hide yes)
			(effects
				(font
					(size 1 1)
					(thickness 0.15)
				)
				(justify mirror)
			)
		)
		(property "License" "Apache-2.0"
			(at 0 0 0)
			(unlocked yes)
			(layer "B.Fab")
			(hide yes)
			(effects
				(font
					(size 1 1)
					(thickness 0.15)
				)
				(justify mirror)
			)
		)
		(property "Author" "Antmicro"
			(at 0 0 0)
			(unlocked yes)
			(layer "B.Fab")
			(hide yes)
			(effects
				(font
					(size 1 1)
					(thickness 0.15)
				)
				(justify mirror)
			)
		)
		(property "Tolerance" "1%"
			(at 0 0 0)
			(unlocked yes)
			(layer "B.Fab")
			(hide yes)
			(effects
				(font
					(size 1 1)
					(thickness 0.15)
				)
				(justify mirror)
			)
		)
		(sheetname "/Supply/")
		(sheetfile "supply.kicad_sch")
		(attr smd)
		(fp_rect
			(start -0.925 0.47)
			(end 0.925 -0.47)
			(stroke
				(width 0.05)
				(type default)
			)
			(fill no)
			(layer "B.CrtYd")
		)
		(fp_rect
			(start -0.5 0.25)
			(end 0.5 -0.25)
			(stroke
				(width 0.15)
				(type solid)
			)
			(fill no)
			(layer "B.Fab")
		)
		(fp_text user "License: Apache-2.0"
			(at -0.95 -5.169 180)
			(layer "B.Fab")
			(effects
				(font
					(size 0.7 0.7)
					(thickness 0.15)
				)
				(justify left bottom mirror)
			)
		)
		(fp_text user "Author: Antmicro"
			(at -0.95 -4.169 180)
			(layer "B.Fab")
			(effects
				(font
					(size 0.7 0.7)
					(thickness 0.15)
				)
				(justify left bottom mirror)
			)
		)
		(fp_text user "${REFERENCE}"
			(at -0.95 -3.168 180)
			(layer "B.Fab")
			(effects
				(font
					(size 0.7 0.7)
					(thickness 0.15)
				)
				(justify left bottom mirror)
			)
		)
		(pad "1" smd roundrect
			(at -0.48 0)
			(size 0.59 0.64)
			(layers "B.Cu" "B.Mask" "B.Paste")
			(roundrect_rratio 0.25)
			(net 3 "GND")
			(pintype "passive")
		)
		(pad "2" smd roundrect
			(at 0.48 0)
			(size 0.59 0.64)
			(layers "B.Cu" "B.Mask" "B.Paste")
			(roundrect_rratio 0.25)
			(net 350 "/Supply/EN_3V3")
			(pintype "passive")
		)
	)
	(footprint "antmicro-footprints:R_0402_1005Metric"
		(layer "B.Cu")
		(at 78.492962 153.6415 90)
		(descr "Resistor SMD 0402")
		(tags "resistor SMD 0402")
		(property "Reference" "R260"
			(at -3.725 0.425 90)
			(layer "B.SilkS")
			(effects
				(font
					(size 0.7 0.7)
					(thickness 0.15)
				)
				(justify right bottom mirror)
			)
		)
		(property "Value" "R_100k_0402"
			(at -1.011843 -1.772047 90)
			(layer "B.Fab")
			(effects
				(font
					(size 0.7 0.7)
					(thickness 0.15)
				)
				(justify right bottom mirror)
			)
		)
		(property "Datasheet" "https://www.bourns.com/docs/product-datasheets/cr.pdf"
			(at 0 0 90)
			(layer "B.Fab")
			(hide yes)
			(effects
				(font
					(size 1.27 1.27)
					(thickness 0.15)
				)
			)
		)
		(property "MPN" "CR0402-FX-1003GLF"
			(at 0 0 90)
			(unlocked yes)
			(layer "B.Fab")
			(hide yes)
			(effects
				(font
					(size 1 1)
					(thickness 0.15)
				)
				(justify mirror)
			)
		)
		(property "Manufacturer" "Bourns"
			(at 0 0 90)
			(unlocked yes)
			(layer "B.Fab")
			(hide yes)
			(effects
				(font
					(size 1 1)
					(thickness 0.15)
				)
				(justify mirror)
			)
		)
		(property "License" "Apache-2.0"
			(at 0 0 90)
			(unlocked yes)
			(layer "B.Fab")
			(hide yes)
			(effects
				(font
					(size 1 1)
					(thickness 0.15)
				)
				(justify mirror)
			)
		)
		(property "Author" "Antmicro"
			(at 0 0 90)
			(unlocked yes)
			(layer "B.Fab")
			(hide yes)
			(effects
				(font
					(size 1 1)
					(thickness 0.15)
				)
				(justify mirror)
			)
		)
		(property "Val" "100k"
			(at 0 0 90)
			(unlocked yes)
			(layer "B.Fab")
			(hide yes)
			(effects
				(font
					(size 1 1)
					(thickness 0.15)
				)
				(justify mirror)
			)
		)
		(property "Tolerance" "1%"
			(at 0 0 90)
			(unlocked yes)
			(layer "B.Fab")
			(hide yes)
			(effects
				(font
					(size 1 1)
					(thickness 0.15)
				)
				(justify mirror)
			)
		)
		(sheetname "/Compute module/")
		(sheetfile "compute-module.kicad_sch")
		(attr smd)
		(fp_rect
			(start -0.925 0.47)
			(end 0.925 -0.47)
			(stroke
				(width 0.05)
				(type default)
			)
			(fill no)
			(layer "B.CrtYd")
		)
		(fp_rect
			(start -0.5 0.25)
			(end 0.5 -0.25)
			(stroke
				(width 0.15)
				(type solid)
			)
			(fill no)
			(layer "B.Fab")
		)
		(fp_text user "Author: Antmicro"
			(at -0.95 -4.169 270)
			(layer "B.Fab")
			(effects
				(font
					(size 0.7 0.7)
					(thickness 0.15)
				)
				(justify left bottom mirror)
			)
		)
		(fp_text user "${REFERENCE}"
			(at -0.95 -3.168 270)
			(layer "B.Fab")
			(effects
				(font
					(size 0.7 0.7)
					(thickness 0.15)
				)
				(justify left bottom mirror)
			)
		)
		(fp_text user "License: Apache-2.0"
			(at -0.95 -5.169 270)
			(layer "B.Fab")
			(effects
				(font
					(size 0.7 0.7)
					(thickness 0.15)
				)
				(justify left bottom mirror)
			)
		)
		(pad "1" smd roundrect
			(at -0.48 0 90)
			(size 0.59 0.64)
			(layers "B.Cu" "B.Mask" "B.Paste")
			(roundrect_rratio 0.25)
			(net 3 "GND")
			(pintype "passive")
		)
		(pad "2" smd roundrect
			(at 0.48 0 90)
			(size 0.59 0.64)
			(layers "B.Cu" "B.Mask" "B.Paste")
			(roundrect_rratio 0.25)
			(net 231 "/Compute module/PolarfireID")
			(pintype "passive")
		)
	)
	(footprint "antmicro-footprints:SOT-523"
		(layer "B.Cu")
		(at 75.642962 128.2665 180)
		(property "Reference" "Q904"
			(at 1.155 -0.22 0)
			(layer "B.SilkS")
			(effects
				(font
					(size 0.7 0.7)
					(thickness 0.15)
				)
				(justify left bottom mirror)
			)
		)
		(property "Value" "PJE138K"
			(at 0.1 -1.824 0)
			(layer "B.Fab")
			(effects
				(font
					(size 0.7 0.7)
					(thickness 0.15)
				)
				(justify left bottom mirror)
			)
		)
		(property "Datasheet" "https://www.mouser.com/datasheet/2/1057/PJE138K-1876698.pdf"
			(at 0 0 180)
			(layer "B.Fab")
			(hide yes)
			(effects
				(font
					(size 1.27 1.27)
					(thickness 0.15)
				)
			)
		)
		(property "MPN" "PJE138K_R1_00001"
			(at 0 0 180)
			(unlocked yes)
			(layer "B.Fab")
			(hide yes)
			(effects
				(font
					(size 1 1)
					(thickness 0.15)
				)
				(justify mirror)
			)
		)
		(property "Manufacturer" "PANJIT"
			(at 0 0 180)
			(unlocked yes)
			(layer "B.Fab")
			(hide yes)
			(effects
				(font
					(size 1 1)
					(thickness 0.15)
				)
				(justify mirror)
			)
		)
		(property "Author" "Antmicro"
			(at 0 0 180)
			(unlocked yes)
			(layer "B.Fab")
			(hide yes)
			(effects
				(font
					(size 1 1)
					(thickness 0.15)
				)
				(justify mirror)
			)
		)
		(property "License" "Apache-2.0"
			(at 0 0 180)
			(unlocked yes)
			(layer "B.Fab")
			(hide yes)
			(effects
				(font
					(size 1 1)
					(thickness 0.15)
				)
				(justify mirror)
			)
		)
		(sheetname "/USB/")
		(sheetfile "usb.kicad_sch")
		(attr smd)
		(fp_line
			(start -0.277 0.551)
			(end -0.277 0.75)
			(stroke
				(width 0.15)
				(type solid)
			)
			(layer "B.SilkS")
		)
		(fp_line
			(start -0.725 0.551)
			(end -0.277 0.551)
			(stroke
				(width 0.15)
				(type solid)
			)
			(layer "B.SilkS")
		)
		(fp_line
			(start -0.927 0.351)
			(end -0.725 0.551)
			(stroke
				(width 0.15)
				(type solid)
			)
			(layer "B.SilkS")
		)
		(fp_line
			(start -0.927 0.051)
			(end -0.927 0.351)
			(stroke
				(width 0.15)
				(type solid)
			)
			(layer "B.SilkS")
		)
		(fp_circle
			(center -0.9652 -0.9652)
			(end -0.9152 -0.9652)
			(stroke
				(width 0.15)
				(type solid)
			)
			(fill yes)
			(layer "B.SilkS")
		)
		(fp_line
			(start 1.1 1.16)
			(end 1.1 -1.15)
			(stroke
				(width 0.05)
				(type solid)
			)
			(layer "B.CrtYd")
		)
		(fp_line
			(start -1.12 1.16)
			(end 1.1 1.16)
			(stroke
				(width 0.05)
				(type solid)
			)
			(layer "B.CrtYd")
		)
		(fp_line
			(start -1.12 1.16)
			(end -1.12 -1.15)
			(stroke
				(width 0.05)
				(type solid)
			)
			(layer "B.CrtYd")
		)
		(fp_line
			(start -1.12 -1.15)
			(end 1.1 -1.15)
			(stroke
				(width 0.05)
				(type solid)
			)
			(layer "B.CrtYd")
		)
		(fp_line
			(start 0.8 0.425)
			(end 0.8 -0.424)
			(stroke
				(width 0.15)
				(type solid)
			)
			(layer "B.Fab")
		)
		(fp_line
			(start 0.8 0.425)
			(end -0.652 0.425)
			(stroke
				(width 0.15)
				(type solid)
			)
			(layer "B.Fab")
		)
		(fp_line
			(start 0.8 -0.424)
			(end -0.802 -0.424)
			(stroke
				(width 0.15)
				(type solid)
			)
			(layer "B.Fab")
		)
		(fp_line
			(start -0.652 0.425)
			(end -0.802 0.276)
			(stroke
				(width 0.15)
				(type solid)
			)
			(layer "B.Fab")
		)
		(fp_line
			(start -0.802 0.276)
			(end -0.802 -0.424)
			(stroke
				(width 0.15)
				(type solid)
			)
			(layer "B.Fab")
		)
		(fp_circle
			(center -0.9652 -0.9652)
			(end -0.9144 -0.9652)
			(stroke
				(width 0.15)
				(type solid)
			)
			(fill no)
			(layer "B.Fab")
		)
		(fp_text user "Author: Antmicro"
			(at -1.12 -6.224 0)
			(layer "B.Fab")
			(effects
				(font
					(size 0.7 0.7)
					(thickness 0.15)
				)
				(justify left bottom mirror)
			)
		)
		(fp_text user "License: Apache-2.0"
			(at -1.12 -5.024 0)
			(layer "B.Fab")
			(effects
				(font
					(size 0.7 0.7)
					(thickness 0.15)
				)
				(justify left bottom mirror)
			)
		)
		(fp_text user "${REFERENCE}"
			(at -1.12 -3.824 0)
			(layer "B.Fab")
			(effects
				(font
					(size 0.7 0.7)
					(thickness 0.15)
				)
				(justify left bottom mirror)
			)
		)
		(pad "1" smd rect
			(at -0.5 -0.65 180)
			(size 0.4 0.51)
			(layers "B.Cu" "B.Mask" "B.Paste")
			(net 338 "/USB/USBD_IN_EN")
			(pinfunction "G")
			(pintype "input")
		)
		(pad "2" smd rect
			(at 0.498 -0.65 180)
			(size 0.4 0.51)
			(layers "B.Cu" "B.Mask" "B.Paste")
			(net 3 "GND")
			(pinfunction "S")
			(pintype "passive")
		)
		(pad "3" smd rect
			(at 0 0.652 180)
			(size 0.4 0.51)
			(layers "B.Cu" "B.Mask" "B.Paste")
			(net 341 "Net-(Q902-G)")
			(pinfunction "D")
			(pintype "passive")
		)
	)
)
